(kicad_pcb
	(version 20260206)
	(generator "pcbnew")
	(generator_version "10.0")
	(general
		(thickness 1.6)
		(legacy_teardrops no)
	)
	(paper "A4")
	(title_block
		(title "panther-plus-userver — 13130-1b_20150205.brd")
		(comment 1 "Honey Badger (Wiwynn) / footprint 1214 of 1509 (DIMM3), pads 51-57 of 210")
	)
	(layers
		(0 "F.Cu" signal "TOP")
		(4 "In1.Cu" signal "L2")
		(6 "In2.Cu" signal "L3")
		(8 "In3.Cu" signal "L4")
		(10 "In4.Cu" signal "L5")
		(12 "In5.Cu" signal "L6")
		(14 "In6.Cu" signal "L7")
		(16 "In7.Cu" signal "L8")
		(18 "In8.Cu" signal "L9")
		(20 "In9.Cu" signal "L10")
		(22 "In10.Cu" signal "L11")
		(2 "B.Cu" signal "BOTTOM")
		(9 "F.Adhes" user "F.Adhesive")
		(11 "B.Adhes" user "B.Adhesive")
		(13 "F.Paste" user "Package Geometry/Pastemask Top")
		(15 "B.Paste" user "Package Geometry/Pastemask Bottom")
		(5 "F.SilkS" user "Ref Des/Silkscreen Top")
		(7 "B.SilkS" user "Ref Des/Silkscreen Bottom")
		(1 "F.Mask" user "Board Geometry/Soldermask Top")
		(3 "B.Mask" user "Board Geometry/Soldermask Bottom")
		(17 "Dwgs.User" user "User.Drawings")
		(19 "Cmts.User" user "User.Comments")
		(21 "Eco1.User" user "User.Eco1")
		(23 "Eco2.User" user "User.Eco2")
		(25 "Edge.Cuts" user "Board Geometry/Outline")
		(27 "Margin" user)
		(31 "F.CrtYd" user "Package Geometry/Place Bound Top")
		(29 "B.CrtYd" user "Package Geometry/Place Bound Bottom")
		(35 "F.Fab" user "Ref Des/Assembly Top")
		(33 "B.Fab" user "Ref Des/Assembly Bottom")
	)
	(footprint ""
		(layer "B.Cu")
		(at 159.999934 -5.790692)
		(property "Reference" "DIMM3"
			(at 0 0 0)
			(layer "B.SilkS")
			(hide yes)
			(effects
				(font
					(size 1.27 1.27)
				)
				(justify mirror)
			)
		)
		(property "Value" "DDR3-204P-142-COLAY-1-GP-U"
			(at 41.312338 -16.676878 0)
			(unlocked yes)
			(layer "B.Fab")
			(hide yes)
			(effects
				(font
					(size 1.016 1.016)
					(thickness 0.1524)
				)
				(justify mirror)
			)
		)
		(property "Device Type" "AS0A626-J8R6-7H-COLAY-1"
			(at 41.312338 -18.200878 0)
			(unlocked yes)
			(layer "B.Fab")
			(hide yes)
			(effects
				(font
					(size 1.016 1.016)
					(thickness 0.1524)
				)
				(justify mirror)
			)
		)
		(duplicate_pad_numbers_are_jumpers no)
		(pad "49" smd custom
			(at -17.249902 -4.100068 180)
			(size 0.1143 0.1143)
			(layers "B.Cu" "B.Mask" "B.Paste")
			(net "M_B_DQ18")
			(options
				(clearance outline)
				(anchor circle)
			)
			(primitives
				(gr_poly
					(pts
						(xy 0 -0.9017) (xy -0.03175 -0.89916) (xy -0.0635 -0.889) (xy -0.09144 -0.87376) (xy -0.11684 -0.85344)
						(xy -0.13716 -0.82804) (xy -0.1524 -0.8001) (xy -0.16256 -0.76835) (xy -0.1651 -0.7366) (xy -0.1651 -0.44958)
						(xy -0.17272 -0.44196) (xy -0.19812 -0.4064) (xy -0.2032 -0.39624) (xy -0.20701 -0.38735) (xy -0.21209 -0.37719)
						(xy -0.2159 -0.36703) (xy -0.21844 -0.35687) (xy -0.22225 -0.34544) (xy -0.22352 -0.33528) (xy -0.22606 -0.32512)
						(xy -0.22733 -0.31369) (xy -0.22733 -0.30353) (xy -0.2286 -0.2921) (xy -0.22733 -0.28067) (xy -0.22733 -0.27051)
						(xy -0.22606 -0.25908) (xy -0.22352 -0.24892) (xy -0.22225 -0.23876) (xy -0.21844 -0.22733) (xy -0.2159 -0.21717)
						(xy -0.21209 -0.20701) (xy -0.20701 -0.19685) (xy -0.2032 -0.18796) (xy -0.19812 -0.1778) (xy -0.17272 -0.14224)
						(xy -0.1651 -0.13462) (xy -0.1651 0.7366) (xy -0.16256 0.76835) (xy -0.1524 0.8001) (xy -0.13716 0.82804)
						(xy -0.11684 0.85344) (xy -0.09144 0.87376) (xy -0.0635 0.889) (xy -0.03175 0.89916) (xy 0 0.9017)
						(xy 0.03175 0.89916) (xy 0.0635 0.889) (xy 0.09144 0.87376) (xy 0.11684 0.85344) (xy 0.13716 0.82804)
						(xy 0.1524 0.8001) (xy 0.16256 0.76835) (xy 0.1651 0.7366) (xy 0.1651 -0.13462) (xy 0.17272 -0.14224)
						(xy 0.19812 -0.1778) (xy 0.2032 -0.18796) (xy 0.20701 -0.19685) (xy 0.21209 -0.20701) (xy 0.2159 -0.21717)
						(xy 0.21844 -0.22733) (xy 0.22225 -0.23876) (xy 0.22352 -0.24892) (xy 0.22606 -0.25908) (xy 0.22733 -0.27051)
						(xy 0.22733 -0.28067) (xy 0.2286 -0.2921) (xy 0.22733 -0.30353) (xy 0.22733 -0.31369) (xy 0.22606 -0.32512)
						(xy 0.22352 -0.33528) (xy 0.22225 -0.34544) (xy 0.21844 -0.35687) (xy 0.2159 -0.36703) (xy 0.21209 -0.37719)
						(xy 0.20701 -0.38735) (xy 0.2032 -0.39624) (xy 0.19812 -0.4064) (xy 0.17272 -0.44196) (xy 0.1651 -0.44958)
						(xy 0.1651 -0.7366) (xy 0.16256 -0.76835) (xy 0.1524 -0.8001) (xy 0.13716 -0.82804) (xy 0.11684 -0.85344)
						(xy 0.09144 -0.87376) (xy 0.0635 -0.889) (xy 0.03175 -0.89916)
					)
					(width 0)
					(fill yes)
				)
			)
		)
		(pad "50" smd custom
			(at -16.949928 4.100068 180)
			(size 0.1143 0.1143)
			(layers "B.Cu" "B.Mask" "B.Paste")
			(net "M_B_DQ23")
			(options
				(clearance outline)
				(anchor circle)
			)
			(primitives
				(gr_poly
					(pts
						(xy 0 -0.9017) (xy -0.03175 -0.89916) (xy -0.0635 -0.889) (xy -0.09144 -0.87376) (xy -0.11684 -0.85344)
						(xy -0.13716 -0.82804) (xy -0.1524 -0.8001) (xy -0.16256 -0.76835) (xy -0.1651 -0.7366) (xy -0.1651 0.13462)
						(xy -0.17272 0.14224) (xy -0.19812 0.1778) (xy -0.2032 0.18796) (xy -0.20701 0.19685) (xy -0.21209 0.20701)
						(xy -0.2159 0.21717) (xy -0.21844 0.22733) (xy -0.22225 0.23876) (xy -0.22352 0.24892) (xy -0.22606 0.25908)
						(xy -0.22733 0.27051) (xy -0.22733 0.28067) (xy -0.2286 0.2921) (xy -0.22733 0.30353) (xy -0.22733 0.31369)
						(xy -0.22606 0.32512) (xy -0.22352 0.33528) (xy -0.22225 0.34544) (xy -0.21844 0.35687) (xy -0.2159 0.36703)
						(xy -0.21209 0.37719) (xy -0.20701 0.38735) (xy -0.2032 0.39624) (xy -0.19812 0.4064) (xy -0.17272 0.44196)
						(xy -0.1651 0.44958) (xy -0.1651 0.7366) (xy -0.16256 0.76835) (xy -0.1524 0.8001) (xy -0.13716 0.82804)
						(xy -0.11684 0.85344) (xy -0.09144 0.87376) (xy -0.0635 0.889) (xy -0.03175 0.89916) (xy 0 0.9017)
						(xy 0.03175 0.89916) (xy 0.0635 0.889) (xy 0.09144 0.87376) (xy 0.11684 0.85344) (xy 0.13716 0.82804)
						(xy 0.1524 0.8001) (xy 0.16256 0.76835) (xy 0.1651 0.7366) (xy 0.1651 0.44958) (xy 0.17272 0.44196)
						(xy 0.19812 0.4064) (xy 0.2032 0.39624) (xy 0.20701 0.38735) (xy 0.21209 0.37719) (xy 0.2159 0.36703)
						(xy 0.21844 0.35687) (xy 0.22225 0.34544) (xy 0.22352 0.33528) (xy 0.22606 0.32512) (xy 0.22733 0.31369)
						(xy 0.22733 0.30353) (xy 0.2286 0.2921) (xy 0.22733 0.28067) (xy 0.22733 0.27051) (xy 0.22606 0.25908)
						(xy 0.22352 0.24892) (xy 0.22225 0.23876) (xy 0.21844 0.22733) (xy 0.2159 0.21717) (xy 0.21209 0.20701)
						(xy 0.20701 0.19685) (xy 0.2032 0.18796) (xy 0.19812 0.1778) (xy 0.17272 0.14224) (xy 0.1651 0.13462)
						(xy 0.1651 -0.7366) (xy 0.16256 -0.76835) (xy 0.1524 -0.8001) (xy 0.13716 -0.82804) (xy 0.11684 -0.85344)
						(xy 0.09144 -0.87376) (xy 0.0635 -0.889) (xy 0.03175 -0.89916)
					)
					(width 0)
					(fill yes)
				)
			)
		)
		(pad "51" smd custom
			(at -16.649954 -4.100068 180)
			(size 0.1143 0.1143)
			(layers "B.Cu" "B.Mask" "B.Paste")
			(net "M_B_DQ19")
			(options
				(clearance outline)
				(anchor circle)
			)
			(primitives
				(gr_poly
					(pts
						(xy 0 -0.9017) (xy -0.03175 -0.89916) (xy -0.0635 -0.889) (xy -0.09144 -0.87376) (xy -0.11684 -0.85344)
						(xy -0.13716 -0.82804) (xy -0.1524 -0.8001) (xy -0.16256 -0.76835) (xy -0.1651 -0.7366) (xy -0.1651 -0.19685)
						(xy -0.17272 -0.18923) (xy -0.17907 -0.18034) (xy -0.18669 -0.17145) (xy -0.19177 -0.16256) (xy -0.19812 -0.15367)
						(xy -0.20828 -0.13335) (xy -0.21971 -0.10287) (xy -0.22225 -0.09271) (xy -0.22479 -0.08128) (xy -0.22606 -0.07112)
						(xy -0.2286 -0.05969) (xy -0.2286 -0.01651) (xy -0.22606 -0.00508) (xy -0.22479 0.00508) (xy -0.22225 0.01651)
						(xy -0.21971 0.02667) (xy -0.20828 0.05715) (xy -0.19812 0.07747) (xy -0.19177 0.08636) (xy -0.18669 0.09525)
						(xy -0.17907 0.10414) (xy -0.17272 0.11303) (xy -0.1651 0.12065) (xy -0.1651 0.7366) (xy -0.16256 0.76835)
						(xy -0.1524 0.8001) (xy -0.13716 0.82804) (xy -0.11684 0.85344) (xy -0.09144 0.87376) (xy -0.0635 0.889)
						(xy -0.03175 0.89916) (xy 0 0.9017) (xy 0.03175 0.89916) (xy 0.0635 0.889) (xy 0.09144 0.87376)
						(xy 0.11684 0.85344) (xy 0.13716 0.82804) (xy 0.1524 0.8001) (xy 0.16256 0.76835) (xy 0.1651 0.7366)
						(xy 0.1651 0.11938) (xy 0.17272 0.11176) (xy 0.19812 0.0762) (xy 0.2032 0.06604) (xy 0.20701 0.05715)
						(xy 0.21209 0.04699) (xy 0.2159 0.03683) (xy 0.21844 0.02667) (xy 0.22225 0.01524) (xy 0.22352 0.00508)
						(xy 0.22606 -0.00508) (xy 0.22733 -0.01651) (xy 0.22733 -0.02667) (xy 0.2286 -0.0381) (xy 0.22733 -0.04953)
						(xy 0.22733 -0.05969) (xy 0.22606 -0.07112) (xy 0.22352 -0.08128) (xy 0.22225 -0.09144) (xy 0.21844 -0.10287)
						(xy 0.2159 -0.11303) (xy 0.21209 -0.12319) (xy 0.20701 -0.13335) (xy 0.2032 -0.14224) (xy 0.19812 -0.1524)
						(xy 0.17272 -0.18796) (xy 0.1651 -0.19558) (xy 0.1651 -0.7366) (xy 0.16256 -0.76835) (xy 0.1524 -0.8001)
						(xy 0.13716 -0.82804) (xy 0.11684 -0.85344) (xy 0.09144 -0.87376) (xy 0.0635 -0.889) (xy 0.03175 -0.89916)
					)
					(width 0)
					(fill yes)
				)
			)
		)
		(pad "52" smd custom
			(at -16.34998 4.100068 180)
			(size 0.1143 0.1143)
			(layers "B.Cu" "B.Mask" "B.Paste")
			(net "GND")
			(options
				(clearance outline)
				(anchor circle)
			)
			(primitives
				(gr_poly
					(pts
						(xy 0 -0.9017) (xy -0.03175 -0.89916) (xy -0.0635 -0.889) (xy -0.09144 -0.87376) (xy -0.11684 -0.85344)
						(xy -0.13716 -0.82804) (xy -0.1524 -0.8001) (xy -0.16256 -0.76835) (xy -0.1651 -0.7366) (xy -0.1651 -0.11938)
						(xy -0.17272 -0.11176) (xy -0.19812 -0.0762) (xy -0.2032 -0.06604) (xy -0.20701 -0.05715) (xy -0.21209 -0.04699)
						(xy -0.2159 -0.03683) (xy -0.21844 -0.02667) (xy -0.22225 -0.01524) (xy -0.22352 -0.00508) (xy -0.22606 0.00508)
						(xy -0.22733 0.01651) (xy -0.22733 0.02667) (xy -0.2286 0.0381) (xy -0.22733 0.04953) (xy -0.22733 0.05969)
						(xy -0.22606 0.07112) (xy -0.22352 0.08128) (xy -0.22225 0.09144) (xy -0.21844 0.10287) (xy -0.2159 0.11303)
						(xy -0.21209 0.12319) (xy -0.20701 0.13335) (xy -0.2032 0.14224) (xy -0.19812 0.1524) (xy -0.17272 0.18796)
						(xy -0.1651 0.19558) (xy -0.1651 0.7366) (xy -0.16256 0.76835) (xy -0.1524 0.8001) (xy -0.13716 0.82804)
						(xy -0.11684 0.85344) (xy -0.09144 0.87376) (xy -0.0635 0.889) (xy -0.03175 0.89916) (xy 0 0.9017)
						(xy 0.03175 0.89916) (xy 0.0635 0.889) (xy 0.09144 0.87376) (xy 0.11684 0.85344) (xy 0.13716 0.82804)
						(xy 0.1524 0.8001) (xy 0.16256 0.76835) (xy 0.1651 0.7366) (xy 0.1651 0.19685) (xy 0.17272 0.18923)
						(xy 0.17907 0.18034) (xy 0.18669 0.17145) (xy 0.19177 0.16256) (xy 0.19812 0.15367) (xy 0.20828 0.13335)
						(xy 0.21971 0.10287) (xy 0.22225 0.09271) (xy 0.22479 0.08128) (xy 0.22606 0.07112) (xy 0.2286 0.05969)
						(xy 0.2286 0.01651) (xy 0.22606 0.00508) (xy 0.22479 -0.00508) (xy 0.22225 -0.01651) (xy 0.21971 -0.02667)
						(xy 0.20828 -0.05715) (xy 0.19812 -0.07747) (xy 0.19177 -0.08636) (xy 0.18669 -0.09525) (xy 0.17907 -0.10414)
						(xy 0.17272 -0.11303) (xy 0.1651 -0.12065) (xy 0.1651 -0.7366) (xy 0.16256 -0.76835) (xy 0.1524 -0.8001)
						(xy 0.13716 -0.82804) (xy 0.11684 -0.85344) (xy 0.09144 -0.87376) (xy 0.0635 -0.889) (xy 0.03175 -0.89916)
					)
					(width 0)
					(fill yes)
				)
			)
		)
		(pad "53" smd custom
			(at -16.050006 -4.100068 180)
			(size 0.1143 0.1143)
			(layers "B.Cu" "B.Mask" "B.Paste")
			(net "GND")
			(options
				(clearance outline)
				(anchor circle)
			)
			(primitives
				(gr_poly
					(pts
						(xy 0 -0.9017) (xy -0.03175 -0.89916) (xy -0.0635 -0.889) (xy -0.09144 -0.87376) (xy -0.11684 -0.85344)
						(xy -0.13716 -0.82804) (xy -0.1524 -0.8001) (xy -0.16256 -0.76835) (xy -0.1651 -0.7366) (xy -0.1651 -0.44958)
						(xy -0.17272 -0.44196) (xy -0.19812 -0.4064) (xy -0.2032 -0.39624) (xy -0.20701 -0.38735) (xy -0.21209 -0.37719)
						(xy -0.2159 -0.36703) (xy -0.21844 -0.35687) (xy -0.22225 -0.34544) (xy -0.22352 -0.33528) (xy -0.22606 -0.32512)
						(xy -0.22733 -0.31369) (xy -0.22733 -0.30353) (xy -0.2286 -0.2921) (xy -0.22733 -0.28067) (xy -0.22733 -0.27051)
						(xy -0.22606 -0.25908) (xy -0.22352 -0.24892) (xy -0.22225 -0.23876) (xy -0.21844 -0.22733) (xy -0.2159 -0.21717)
						(xy -0.21209 -0.20701) (xy -0.20701 -0.19685) (xy -0.2032 -0.18796) (xy -0.19812 -0.1778) (xy -0.17272 -0.14224)
						(xy -0.1651 -0.13462) (xy -0.1651 0.7366) (xy -0.16256 0.76835) (xy -0.1524 0.8001) (xy -0.13716 0.82804)
						(xy -0.11684 0.85344) (xy -0.09144 0.87376) (xy -0.0635 0.889) (xy -0.03175 0.89916) (xy 0 0.9017)
						(xy 0.03175 0.89916) (xy 0.0635 0.889) (xy 0.09144 0.87376) (xy 0.11684 0.85344) (xy 0.13716 0.82804)
						(xy 0.1524 0.8001) (xy 0.16256 0.76835) (xy 0.1651 0.7366) (xy 0.1651 -0.13462) (xy 0.17272 -0.14224)
						(xy 0.19812 -0.1778) (xy 0.2032 -0.18796) (xy 0.20701 -0.19685) (xy 0.21209 -0.20701) (xy 0.2159 -0.21717)
						(xy 0.21844 -0.22733) (xy 0.22225 -0.23876) (xy 0.22352 -0.24892) (xy 0.22606 -0.25908) (xy 0.22733 -0.27051)
						(xy 0.22733 -0.28067) (xy 0.2286 -0.2921) (xy 0.22733 -0.30353) (xy 0.22733 -0.31369) (xy 0.22606 -0.32512)
						(xy 0.22352 -0.33528) (xy 0.22225 -0.34544) (xy 0.21844 -0.35687) (xy 0.2159 -0.36703) (xy 0.21209 -0.37719)
						(xy 0.20701 -0.38735) (xy 0.2032 -0.39624) (xy 0.19812 -0.4064) (xy 0.17272 -0.44196) (xy 0.1651 -0.44958)
						(xy 0.1651 -0.7366) (xy 0.16256 -0.76835) (xy 0.1524 -0.8001) (xy 0.13716 -0.82804) (xy 0.11684 -0.85344)
						(xy 0.09144 -0.87376) (xy 0.0635 -0.889) (xy 0.03175 -0.89916)
					)
					(width 0)
					(fill yes)
				)
			)
		)
		(pad "54" smd custom
			(at -15.750032 4.100068 180)
			(size 0.1143 0.1143)
			(layers "B.Cu" "B.Mask" "B.Paste")
			(net "M_B_DQ28")
			(options
				(clearance outline)
				(anchor circle)
			)
			(primitives
				(gr_poly
					(pts
						(xy 0 -0.9017) (xy -0.03175 -0.89916) (xy -0.0635 -0.889) (xy -0.09144 -0.87376) (xy -0.11684 -0.85344)
						(xy -0.13716 -0.82804) (xy -0.1524 -0.8001) (xy -0.16256 -0.76835) (xy -0.1651 -0.7366) (xy -0.1651 0.13462)
						(xy -0.17272 0.14224) (xy -0.19812 0.1778) (xy -0.2032 0.18796) (xy -0.20701 0.19685) (xy -0.21209 0.20701)
						(xy -0.2159 0.21717) (xy -0.21844 0.22733) (xy -0.22225 0.23876) (xy -0.22352 0.24892) (xy -0.22606 0.25908)
						(xy -0.22733 0.27051) (xy -0.22733 0.28067) (xy -0.2286 0.2921) (xy -0.22733 0.30353) (xy -0.22733 0.31369)
						(xy -0.22606 0.32512) (xy -0.22352 0.33528) (xy -0.22225 0.34544) (xy -0.21844 0.35687) (xy -0.2159 0.36703)
						(xy -0.21209 0.37719) (xy -0.20701 0.38735) (xy -0.2032 0.39624) (xy -0.19812 0.4064) (xy -0.17272 0.44196)
						(xy -0.1651 0.44958) (xy -0.1651 0.7366) (xy -0.16256 0.76835) (xy -0.1524 0.8001) (xy -0.13716 0.82804)
						(xy -0.11684 0.85344) (xy -0.09144 0.87376) (xy -0.0635 0.889) (xy -0.03175 0.89916) (xy 0 0.9017)
						(xy 0.03175 0.89916) (xy 0.0635 0.889) (xy 0.09144 0.87376) (xy 0.11684 0.85344) (xy 0.13716 0.82804)
						(xy 0.1524 0.8001) (xy 0.16256 0.76835) (xy 0.1651 0.7366) (xy 0.1651 0.44958) (xy 0.17272 0.44196)
						(xy 0.19812 0.4064) (xy 0.2032 0.39624) (xy 0.20701 0.38735) (xy 0.21209 0.37719) (xy 0.2159 0.36703)
						(xy 0.21844 0.35687) (xy 0.22225 0.34544) (xy 0.22352 0.33528) (xy 0.22606 0.32512) (xy 0.22733 0.31369)
						(xy 0.22733 0.30353) (xy 0.2286 0.2921) (xy 0.22733 0.28067) (xy 0.22733 0.27051) (xy 0.22606 0.25908)
						(xy 0.22352 0.24892) (xy 0.22225 0.23876) (xy 0.21844 0.22733) (xy 0.2159 0.21717) (xy 0.21209 0.20701)
						(xy 0.20701 0.19685) (xy 0.2032 0.18796) (xy 0.19812 0.1778) (xy 0.17272 0.14224) (xy 0.1651 0.13462)
						(xy 0.1651 -0.7366) (xy 0.16256 -0.76835) (xy 0.1524 -0.8001) (xy 0.13716 -0.82804) (xy 0.11684 -0.85344)
						(xy 0.09144 -0.87376) (xy 0.0635 -0.889) (xy 0.03175 -0.89916)
					)
					(width 0)
					(fill yes)
				)
			)
		)
		(pad "55" smd custom
			(at -15.450058 -4.100068 180)
			(size 0.1143 0.1143)
			(layers "B.Cu" "B.Mask" "B.Paste")
			(net "M_B_DQ24")
			(options
				(clearance outline)
				(anchor circle)
			)
			(primitives
				(gr_poly
					(pts
						(xy 0 -0.9017) (xy -0.03175 -0.89916) (xy -0.0635 -0.889) (xy -0.09144 -0.87376) (xy -0.11684 -0.85344)
						(xy -0.13716 -0.82804) (xy -0.1524 -0.8001) (xy -0.16256 -0.76835) (xy -0.1651 -0.7366) (xy -0.1651 -0.19685)
						(xy -0.17272 -0.18923) (xy -0.17907 -0.18034) (xy -0.18669 -0.17145) (xy -0.19177 -0.16256) (xy -0.19812 -0.15367)
						(xy -0.20828 -0.13335) (xy -0.21971 -0.10287) (xy -0.22225 -0.09271) (xy -0.22479 -0.08128) (xy -0.22606 -0.07112)
						(xy -0.2286 -0.05969) (xy -0.2286 -0.01651) (xy -0.22606 -0.00508) (xy -0.22479 0.00508) (xy -0.22225 0.01651)
						(xy -0.21971 0.02667) (xy -0.20828 0.05715) (xy -0.19812 0.07747) (xy -0.19177 0.08636) (xy -0.18669 0.09525)
						(xy -0.17907 0.10414) (xy -0.17272 0.11303) (xy -0.1651 0.12065) (xy -0.1651 0.7366) (xy -0.16256 0.76835)
						(xy -0.1524 0.8001) (xy -0.13716 0.82804) (xy -0.11684 0.85344) (xy -0.09144 0.87376) (xy -0.0635 0.889)
						(xy -0.03175 0.89916) (xy 0 0.9017) (xy 0.03175 0.89916) (xy 0.0635 0.889) (xy 0.09144 0.87376)
						(xy 0.11684 0.85344) (xy 0.13716 0.82804) (xy 0.1524 0.8001) (xy 0.16256 0.76835) (xy 0.1651 0.7366)
						(xy 0.1651 0.11938) (xy 0.17272 0.11176) (xy 0.19812 0.0762) (xy 0.2032 0.06604) (xy 0.20701 0.05715)
						(xy 0.21209 0.04699) (xy 0.2159 0.03683) (xy 0.21844 0.02667) (xy 0.22225 0.01524) (xy 0.22352 0.00508)
						(xy 0.22606 -0.00508) (xy 0.22733 -0.01651) (xy 0.22733 -0.02667) (xy 0.2286 -0.0381) (xy 0.22733 -0.04953)
						(xy 0.22733 -0.05969) (xy 0.22606 -0.07112) (xy 0.22352 -0.08128) (xy 0.22225 -0.09144) (xy 0.21844 -0.10287)
						(xy 0.2159 -0.11303) (xy 0.21209 -0.12319) (xy 0.20701 -0.13335) (xy 0.2032 -0.14224) (xy 0.19812 -0.1524)
						(xy 0.17272 -0.18796) (xy 0.1651 -0.19558) (xy 0.1651 -0.7366) (xy 0.16256 -0.76835) (xy 0.1524 -0.8001)
						(xy 0.13716 -0.82804) (xy 0.11684 -0.85344) (xy 0.09144 -0.87376) (xy 0.0635 -0.889) (xy 0.03175 -0.89916)
					)
					(width 0)
					(fill yes)
				)
			)
		)
	)
)
